G04 #@! TF.GenerationSoftware,KiCad,Pcbnew,(5.0.1)-3*
G04 #@! TF.CreationDate,2019-04-10T15:36:06+02:00*
G04 #@! TF.ProjectId,discovery,646973636F766572792E6B696361645F,rev?*
G04 #@! TF.SameCoordinates,PX4c4640PY8a48028*
G04 #@! TF.FileFunction,Glue,Top*
G04 #@! TF.FilePolarity,Positive*
%FSLAX46Y46*%
G04 Gerber Fmt 4.6, Leading zero omitted, Abs format (unit mm)*
%MOMM*%
%LPD*%
G01*
G04 APERTURE LIST*
G04 APERTURE END LIST*
M02*
